FILE_TYPE = MULTI_PHYS_TABLE;

PART 'RAA229126GNPHA0'

{========================================================================================}
:VALUE              | PART_TYPE | MATERIAL | PART_NUMBER    = STANDARD        | LIFECYCLE     | PART_NUMBER   | JEDEC_TYPE   | DESCRIPTION                                             | MANUFTR | MANUF_PN           | RD_CMPLS_LVL | CMPLS_LVL | FROM_PJ      | CLASS | DIP_SMD | DATA                               | EE_CHECK_LIST | FP_ECN | PSL | CREATOR | STATUS | MSD  | ESD_CDM | ESD_HBM | ESD_MM | PIN_LENGTH_SHORT_PIN | PIN_LENGTH_LONG_PIN | CREATEDAY  ;
{========================================================================================}
 'RAA229126GNP#HA0' | 'SMLF'    | 'IC'     | 'AL229126000'(!) = ''              | ''            | 'AL229126000' |'QFN48_THXT'| 'IC CTRL(48P)RAA229126GNP#HA0(QFN)'                     | 'RTT'   | 'RAA229126GNP#HA0' | 'EP(V1)'     | ''        | 'S8Z-CARLOS' | 'IC'  | ''      | 'RTT_RAA229126GNPHA0.pdf'          | ''            | ''     | ''  | ''      | ''     | 'NA' | 'N/A'   | 'N/A'   | 'N/A'  | '0 MILS'             | '0 MILS'            | '20200420'
 'RAA229126GNP#HA0' | 'SMLF'    | 'EMPTY'  | 'AL229126000'(!) = ''              | ''            | 'AL229126000' |'QFN48_THXT'| 'IC CTRL(48P)RAA229126GNP#HA0(QFN)'                     | 'RTT'   | 'RAA229126GNP#HA0' | 'EP(V1)'     | ''        | 'S8Z-CARLOS' | 'IC'  | ''      | 'RTT_RAA229126GNPHA0.pdf'          | ''            | ''     | ''  | ''      | ''     | 'NA' | 'N/A'   | 'N/A'   | 'N/A'  | '0 MILS'             | '0 MILS'            | '20200420'
 'RAA229126GNP#HA0' | 'SMLF'    | 'IC'     | 'AR0S7PPF002'(!) = ''               | ''               | 'AR0S7PPF002' |'QFN48_THXT'| 'PROG IC(48P)RAA229126GNP#HA0(QFN) (checksum:D8F97512)' | 'RTT'   | 'RAA229126GNP#HA0' | 'EP(V1)'     | ''        | 'S7P-FRANK'  | 'IC'  | ''      | 'RTT_RAA229126GNPHA0_D8F97512.pdf' | ''            | ''     | ''  | ''      | ''     | ''   | ''      | ''      | ''     | '0 MILS'             | '0 MILS'            | '20210420'
 'RAA229126GNP#HA0' | 'SMLF'    | 'EMPTY'  | 'AR0S7PPF002'(!) = ''               | ''               | 'AR0S7PPF002' |'QFN48_THXT'| 'PROG IC(48P)RAA229126GNP#HA0(QFN) (checksum:D8F97512)' | 'RTT'   | 'RAA229126GNP#HA0' | 'EP(V1)'     | ''        | 'S7P-FRANK'  | 'IC'  | ''      | 'RTT_RAA229126GNPHA0_D8F97512.pdf' | ''            | ''     | ''  | ''      | ''     | ''   | ''      | ''      | ''     | '0 MILS'             | '0 MILS'            | '20210420'

END_PART

END.

